# BASEBOARD_FAB2 (Tioga Pass) — schematic netlist excerpt (pin names and nets, part order shuffled) for the footprints in the layout excerpt that follows; sources: Cadence DE-HDL packaged netlist, KiCad conversion of Wiwynn_Tioga_Pass_MB.brd

C5G68  CAP_A  22.0UF 4V 20% X6S  pkg 0603V  page 242 : A = PVDDQ_DEF ; B = GND
C4T6  CAP  10UF 4V 20% X6S  pkg 0603LF  page 231 : A = PVPP_ABC ; B = GND
C25W79  CAP  100.0PF 50V 5% COG  pkg 0402LF  page 252 : A = V_IBMC_5V_DDC_SDA_J ; B = GND

(kicad_pcb
	(version 20260206)
	(generator "pcbnew")
	(generator_version "10.0")
	(general
		(thickness 1.6)
		(legacy_teardrops no)
	)
	(paper "A4")
	(title_block
		(title "Wiwynn_Tioga_Pass_MB.brd")
		(comment 1 "Tioga Pass / footprints 2795-2797 of 4770")
	)
	(layers
		(0 "F.Cu" signal "TOP")
		(4 "In1.Cu" signal "L2GND")
		(6 "In2.Cu" signal "L3")
		(8 "In3.Cu" signal "L4GND")
		(10 "In4.Cu" signal "L5")
		(12 "In5.Cu" signal "L6GND")
		(14 "In6.Cu" signal "L7VCC")
		(16 "In7.Cu" signal "L8VCC")
		(18 "In8.Cu" signal "L9GND")
		(20 "In9.Cu" signal "L10")
		(22 "In10.Cu" signal "L11GND")
		(24 "In11.Cu" signal "L12")
		(26 "In12.Cu" signal "L13GND")
		(2 "B.Cu" signal "BOTTOM")
		(9 "F.Adhes" user "F.Adhesive")
		(11 "B.Adhes" user "B.Adhesive")
		(13 "F.Paste" user "Package Geometry/Pastemask Top")
		(15 "B.Paste" user "Package Geometry/Pastemask Bottom")
		(5 "F.SilkS" user "Ref Des/Silkscreen Top")
		(7 "B.SilkS" user "Ref Des/Silkscreen Bottom")
		(1 "F.Mask" user "Board Geometry/Soldermask Top")
		(3 "B.Mask" user "Board Geometry/Soldermask Bottom")
		(17 "Dwgs.User" user "User.Drawings")
		(19 "Cmts.User" user "User.Comments")
		(21 "Eco1.User" user "User.Eco1")
		(23 "Eco2.User" user "User.Eco2")
		(25 "Edge.Cuts" user "Board Geometry/Outline")
		(27 "Margin" user)
		(31 "F.CrtYd" user "Package Geometry/Place Bound Top")
		(29 "B.CrtYd" user "Package Geometry/Place Bound Bottom")
		(35 "F.Fab" user "Ref Des/Assembly Top")
		(33 "B.Fab" user "Ref Des/Assembly Bottom")
	)
	(footprint ""
		(layer "B.Cu")
		(at 318.543432 -17.78 -90)
		(property "Reference" "C4T6"
			(at 0 0 90)
			(layer "B.SilkS")
			(hide yes)
			(effects
				(font
					(size 1.27 1.27)
				)
				(justify mirror)
			)
		)
		(property "Value" ""
			(at 0 0 90)
			(layer "B.Fab")
			(effects
				(font
					(size 1.27 1.27)
				)
				(justify mirror)
			)
		)
		(duplicate_pad_numbers_are_jumpers no)
		(fp_poly
			(pts
				(xy 0.4953 -0.2032) (xy -0.4953 -0.2032) (xy -0.4953 1.6002) (xy 0.4953 1.6002)
			)
			(stroke
				(width 0)
				(type default)
			)
			(fill no)
			(layer "B.CrtYd")
		)
		(fp_line
			(start -0.4953 1.6002)
			(end 0.4953 1.6002)
			(stroke
				(width 0.1)
				(type default)
			)
			(layer "B.Fab")
		)
		(fp_line
			(start 0.4953 1.6002)
			(end 0.4953 -0.2032)
			(stroke
				(width 0.1)
				(type default)
			)
			(layer "B.Fab")
		)
		(fp_line
			(start -0.4953 -0.2032)
			(end -0.4953 1.6002)
			(stroke
				(width 0.1)
				(type default)
			)
			(layer "B.Fab")
		)
		(fp_line
			(start 0.4953 -0.2032)
			(end -0.4953 -0.2032)
			(stroke
				(width 0.1)
				(type default)
			)
			(layer "B.Fab")
		)
		(pad "1" smd rect
			(at 0 0 90)
			(size 0.762 0.889)
			(layers "B.Cu" "B.Mask" "B.Paste")
			(net "PVPP_ABC")
		)
		(pad "2" smd rect
			(at 0 1.397 90)
			(size 0.762 0.889)
			(layers "B.Cu" "B.Mask" "B.Paste")
			(net "GND")
		)
		(zone
			(layer "B.Cu")
			(hatch none 0.5)
			(connect_pads
				(clearance 0)
			)
			(min_thickness 0.25)
			(keepout
				(tracks not_allowed)
				(vias allowed)
				(pads allowed)
				(copperpour not_allowed)
				(footprints allowed)
			)
			(placement
				(enabled no)
				(sheetname "")
			)
			(fill
				(thermal_gap 0.5)
				(thermal_bridge_width 0.5)
				(island_removal_mode 0)
			)
			(polygon
				(pts
					(xy 318.098932 -17.399) (xy 318.098932 -18.161) (xy 317.590932 -18.161) (xy 317.590932 -17.399)
				)
			)
		)
	)
	(footprint ""
		(layer "B.Cu")
		(at 494.706148 -44.533312)
		(property "Reference" "C25W79"
			(at 0.8382 -0.67818 0)
			(unlocked yes)
			(layer "B.SilkS")
			(effects
				(font
					(size 0.4064 0.254)
					(thickness 0.1524)
				)
				(justify left mirror)
			)
		)
		(property "Value" ""
			(at 0 0 0)
			(layer "B.Fab")
			(effects
				(font
					(size 1.27 1.27)
				)
				(justify mirror)
			)
		)
		(duplicate_pad_numbers_are_jumpers no)
		(fp_poly
			(pts
				(xy -0.3048 -0.1016) (xy -0.3048 0.9906) (xy 0.3048 0.9906) (xy 0.3048 -0.1016)
			)
			(stroke
				(width 0)
				(type default)
			)
			(fill no)
			(layer "B.CrtYd")
		)
		(fp_line
			(start -0.3048 -0.1016)
			(end 0.3048 -0.1016)
			(stroke
				(width 0.1)
				(type default)
			)
			(layer "B.Fab")
		)
		(fp_line
			(start -0.3048 0.9906)
			(end -0.3048 -0.1016)
			(stroke
				(width 0.1)
				(type default)
			)
			(layer "B.Fab")
		)
		(fp_line
			(start 0.3048 -0.1016)
			(end 0.3048 0.9906)
			(stroke
				(width 0.1)
				(type default)
			)
			(layer "B.Fab")
		)
		(fp_line
			(start 0.3048 0.9906)
			(end -0.3048 0.9906)
			(stroke
				(width 0.1)
				(type default)
			)
			(layer "B.Fab")
		)
		(pad "1" smd rect
			(at 0 0 180)
			(size 0.508 0.508)
			(layers "B.Cu" "B.Mask" "B.Paste")
			(net "V_IBMC_5V_DDC_SDA_J")
		)
		(pad "2" smd rect
			(at 0 0.889 180)
			(size 0.508 0.508)
			(layers "B.Cu" "B.Mask" "B.Paste")
			(net "GND")
		)
		(zone
			(layer "B.Cu")
			(hatch none 0.5)
			(connect_pads
				(clearance 0)
			)
			(min_thickness 0.25)
			(keepout
				(tracks allowed)
				(vias not_allowed)
				(pads allowed)
				(copperpour not_allowed)
				(footprints allowed)
			)
			(placement
				(enabled no)
				(sheetname "")
			)
			(fill
				(thermal_gap 0.5)
				(thermal_bridge_width 0.5)
				(island_removal_mode 0)
			)
			(polygon
				(pts
					(xy 494.960148 -44.279312) (xy 494.452148 -44.279312) (xy 494.452148 -43.898312) (xy 494.960148 -43.898312)
				)
			)
		)
		(zone
			(layer "B.Cu")
			(hatch none 0.5)
			(connect_pads
				(clearance 0)
			)
			(min_thickness 0.25)
			(keepout
				(tracks not_allowed)
				(vias allowed)
				(pads allowed)
				(copperpour not_allowed)
				(footprints allowed)
			)
			(placement
				(enabled no)
				(sheetname "")
			)
			(fill
				(thermal_gap 0.5)
				(thermal_bridge_width 0.5)
				(island_removal_mode 0)
			)
			(polygon
				(pts
					(xy 494.960148 -43.898312) (xy 494.452148 -43.898312) (xy 494.452148 -44.279312) (xy 494.960148 -44.279312)
				)
			)
		)
	)
	(footprint ""
		(layer "B.Cu")
		(at 258.2164 -140.1826 -90)
		(property "Reference" "C5G68"
			(at -1.14681 0.76708 0)
			(unlocked yes)
			(layer "B.SilkS")
			(effects
				(font
					(size 0.7874 0.5842)
					(thickness 0.1524)
				)
				(justify mirror)
			)
		)
		(property "Value" ""
			(at 0 0 90)
			(layer "B.Fab")
			(effects
				(font
					(size 1.27 1.27)
				)
				(justify mirror)
			)
		)
		(duplicate_pad_numbers_are_jumpers no)
		(fp_rect
			(start -0.4953 -0.2032)
			(end 0.4953 1.6002)
			(stroke
				(width 0)
				(type default)
			)
			(fill no)
			(layer "B.CrtYd")
		)
		(fp_line
			(start -0.4953 1.6002)
			(end 0.4953 1.6002)
			(stroke
				(width 0.1)
				(type default)
			)
			(layer "B.Fab")
		)
		(fp_line
			(start 0.4953 1.6002)
			(end 0.4953 -0.2032)
			(stroke
				(width 0.1)
				(type default)
			)
			(layer "B.Fab")
		)
		(fp_line
			(start -0.4953 -0.2032)
			(end -0.4953 1.6002)
			(stroke
				(width 0.1)
				(type default)
			)
			(layer "B.Fab")
		)
		(fp_line
			(start 0.4953 -0.2032)
			(end -0.4953 -0.2032)
			(stroke
				(width 0.1)
				(type default)
			)
			(layer "B.Fab")
		)
		(pad "1" smd rect
			(at 0 0 90)
			(size 0.762 0.889)
			(layers "B.Cu" "B.Mask" "B.Paste")
			(net "PVDDQ_DEF")
		)
		(pad "2" smd rect
			(at 0 1.397 90)
			(size 0.762 0.889)
			(layers "B.Cu" "B.Mask" "B.Paste")
			(net "GND")
		)
		(zone
			(layer "B.Cu")
			(hatch none 0.5)
			(connect_pads
				(clearance 0)
			)
			(min_thickness 0.25)
			(keepout
				(tracks not_allowed)
				(vias allowed)
				(pads allowed)
				(copperpour not_allowed)
				(footprints allowed)
			)
			(placement
				(enabled no)
				(sheetname "")
			)
			(fill
				(thermal_gap 0.5)
				(thermal_bridge_width 0.5)
				(island_removal_mode 0)
			)
			(polygon
				(pts
					(xy 257.7719 -140.5636) (xy 257.2639 -140.5636) (xy 257.2639 -139.8016) (xy 257.7719 -139.8016)
				)
			)
		)
	)
)
